# S9S_MB_2U (Grand Teton) — schematic netlist excerpt (pin names and nets, part order shuffled) for the footprints in the layout excerpt that follows; sources: Cadence DE-HDL packaged netlist, KiCad conversion of 03242023_DA0F0TMBIJ0_F0T_Motherboard_J_brd_V01_OCP.brd

PC244_P0_8  Q_CAP  22UF 4V 20% X6S  pkg C0805  page 270 : A = PVCCIN_CPU0 ; B = GND
PC2141  Q_CAP  22UF 16V 20% X6S  pkg C0805  page 162 : A = P12V_OCP_V3_2 ; B = GND
R576  Q_RES  49.9 1% CHIP  pkg 0402LF  page 206 : A = FM_DB2000_OE_N ; B = FM_DB2000_1_OE_N

(kicad_pcb
	(version 20260206)
	(generator "pcbnew")
	(generator_version "10.0")
	(general
		(thickness 1.6)
		(legacy_teardrops no)
	)
	(paper "A4")
	(title_block
		(title "03242023_DA0F0TMBIJ0_F0T_Motherboard_J_brd_V01_OCP.brd")
		(comment 1 "Grand Teton / footprints 5358-5360 of 6105")
	)
	(layers
		(0 "F.Cu" signal "TOP")
		(4 "In1.Cu" signal "GND")
		(6 "In2.Cu" signal "IN1")
		(8 "In3.Cu" signal "GND1")
		(10 "In4.Cu" signal "IN2")
		(12 "In5.Cu" signal "GND2")
		(14 "In6.Cu" signal "IN3")
		(16 "In7.Cu" signal "GND3")
		(18 "In8.Cu" signal "VCC")
		(20 "In9.Cu" signal "VCC1")
		(22 "In10.Cu" signal "GND4")
		(24 "In11.Cu" signal "IN4")
		(26 "In12.Cu" signal "GND5")
		(28 "In13.Cu" signal "IN5")
		(30 "In14.Cu" signal "GND6")
		(32 "In15.Cu" signal "IN6")
		(34 "In16.Cu" signal "GND7")
		(2 "B.Cu" signal "BOTTOM")
		(9 "F.Adhes" user "F.Adhesive")
		(11 "B.Adhes" user "B.Adhesive")
		(13 "F.Paste" user "Package Geometry/Pastemask Top")
		(15 "B.Paste" user "Package Geometry/Pastemask Bottom")
		(5 "F.SilkS" user "Ref Des/Silkscreen Top")
		(7 "B.SilkS" user "Ref Des/Silkscreen Bottom")
		(1 "F.Mask" user "Board Geometry/Soldermask Top")
		(3 "B.Mask" user "Board Geometry/Soldermask Bottom")
		(17 "Dwgs.User" user "User.Drawings")
		(19 "Cmts.User" user "User.Comments")
		(21 "Eco1.User" user "User.Eco1")
		(23 "Eco2.User" user "User.Eco2")
		(25 "Edge.Cuts" user "Board Geometry/Outline")
		(27 "Margin" user)
		(31 "F.CrtYd" user "Package Geometry/Place Bound Top")
		(29 "B.CrtYd" user "Package Geometry/Place Bound Bottom")
		(35 "F.Fab" user "Ref Des/Assembly Top")
		(33 "B.Fab" user "Ref Des/Assembly Bottom")
	)
	(footprint ""
		(layer "B.Cu")
		(at 386.214112 -331.60208 -90)
		(property "Reference" "PC244_P0_8"
			(at 0 0 90)
			(layer "B.SilkS")
			(hide yes)
			(effects
				(font
					(size 1.27 1.27)
				)
				(justify mirror)
			)
		)
		(property "Value" ""
			(at 0 0 90)
			(layer "B.Fab")
			(effects
				(font
					(size 1.27 1.27)
				)
				(justify mirror)
			)
		)
		(duplicate_pad_numbers_are_jumpers no)
		(fp_line
			(start -1.524 0.762)
			(end 1.524 0.762)
			(stroke
				(width 0.1524)
				(type default)
			)
			(layer "B.SilkS")
		)
		(fp_line
			(start 1.524 0.762)
			(end 1.524 -0.762)
			(stroke
				(width 0.1524)
				(type default)
			)
			(layer "B.SilkS")
		)
		(fp_line
			(start -1.524 -0.762)
			(end -1.524 0.762)
			(stroke
				(width 0.1524)
				(type default)
			)
			(layer "B.SilkS")
		)
		(fp_line
			(start 1.524 -0.762)
			(end -1.524 -0.762)
			(stroke
				(width 0.1524)
				(type default)
			)
			(layer "B.SilkS")
		)
		(fp_line
			(start -1.1049 0.724916)
			(end -1.1049 -0.724916)
			(stroke
				(width 0.1)
				(type default)
			)
			(layer "B.Fab")
		)
		(fp_line
			(start 1.1049 0.724916)
			(end -1.1049 0.724916)
			(stroke
				(width 0.1)
				(type default)
			)
			(layer "B.Fab")
		)
		(fp_line
			(start -1.1049 -0.724916)
			(end 1.1049 -0.724916)
			(stroke
				(width 0.1)
				(type default)
			)
			(layer "B.Fab")
		)
		(fp_line
			(start 1.1049 -0.724916)
			(end 1.1049 0.724916)
			(stroke
				(width 0.1)
				(type default)
			)
			(layer "B.Fab")
		)
		(pad "1" smd rect
			(at 0.889 0 270)
			(size 1.016 1.27)
			(layers "B.Cu" "B.Mask" "B.Paste")
			(net "PVCCIN_CPU0")
		)
		(pad "2" smd rect
			(at -0.889 0 270)
			(size 1.016 1.27)
			(layers "B.Cu" "B.Mask" "B.Paste")
			(net "GND")
		)
	)
	(footprint ""
		(layer "B.Cu")
		(at 65.828926 -20.04822)
		(property "Reference" "PC2141"
			(at 0 0 0)
			(layer "B.SilkS")
			(hide yes)
			(effects
				(font
					(size 1.27 1.27)
				)
				(justify mirror)
			)
		)
		(property "Value" ""
			(at 0 0 0)
			(layer "B.Fab")
			(effects
				(font
					(size 1.27 1.27)
				)
				(justify mirror)
			)
		)
		(duplicate_pad_numbers_are_jumpers no)
		(fp_line
			(start -1.524 -0.762)
			(end -1.524 0.762)
			(stroke
				(width 0.1524)
				(type default)
			)
			(layer "B.SilkS")
		)
		(fp_line
			(start -1.524 0.762)
			(end 1.524 0.762)
			(stroke
				(width 0.1524)
				(type default)
			)
			(layer "B.SilkS")
		)
		(fp_line
			(start 1.524 -0.762)
			(end -1.524 -0.762)
			(stroke
				(width 0.1524)
				(type default)
			)
			(layer "B.SilkS")
		)
		(fp_line
			(start 1.524 0.762)
			(end 1.524 -0.762)
			(stroke
				(width 0.1524)
				(type default)
			)
			(layer "B.SilkS")
		)
		(fp_line
			(start -1.1049 -0.724916)
			(end 1.1049 -0.724916)
			(stroke
				(width 0.1)
				(type default)
			)
			(layer "B.Fab")
		)
		(fp_line
			(start -1.1049 0.724916)
			(end -1.1049 -0.724916)
			(stroke
				(width 0.1)
				(type default)
			)
			(layer "B.Fab")
		)
		(fp_line
			(start 1.1049 -0.724916)
			(end 1.1049 0.724916)
			(stroke
				(width 0.1)
				(type default)
			)
			(layer "B.Fab")
		)
		(fp_line
			(start 1.1049 0.724916)
			(end -1.1049 0.724916)
			(stroke
				(width 0.1)
				(type default)
			)
			(layer "B.Fab")
		)
		(pad "1" smd rect
			(at 0.889 0)
			(size 1.016 1.27)
			(layers "B.Cu" "B.Mask" "B.Paste")
			(net "P12V_OCP_V3_2")
		)
		(pad "2" smd rect
			(at -0.889 0)
			(size 1.016 1.27)
			(layers "B.Cu" "B.Mask" "B.Paste")
			(net "GND")
		)
	)
	(footprint ""
		(layer "B.Cu")
		(at 229.761796 -128.866392 180)
		(property "Reference" "R576"
			(at 0 0 0)
			(layer "B.SilkS")
			(hide yes)
			(effects
				(font
					(size 1.27 1.27)
				)
				(justify mirror)
			)
		)
		(property "Value" ""
			(at 0 0 0)
			(layer "B.Fab")
			(effects
				(font
					(size 1.27 1.27)
				)
				(justify mirror)
			)
		)
		(duplicate_pad_numbers_are_jumpers no)
		(fp_line
			(start 0.7874 0.4064)
			(end 0.7874 -0.4064)
			(stroke
				(width 0.1524)
				(type default)
			)
			(layer "B.SilkS")
		)
		(fp_line
			(start 0.7874 -0.4064)
			(end -0.7874 -0.4064)
			(stroke
				(width 0.1524)
				(type default)
			)
			(layer "B.SilkS")
		)
		(fp_line
			(start -0.7874 0.4064)
			(end 0.7874 0.4064)
			(stroke
				(width 0.1524)
				(type default)
			)
			(layer "B.SilkS")
		)
		(fp_line
			(start -0.7874 -0.4064)
			(end -0.7874 0.4064)
			(stroke
				(width 0.1524)
				(type default)
			)
			(layer "B.SilkS")
		)
		(fp_line
			(start 0.67945 0.3048)
			(end 0.67945 -0.305054)
			(stroke
				(width 0.1)
				(type default)
			)
			(layer "B.Fab")
		)
		(fp_line
			(start 0.67945 -0.305054)
			(end 0.12065 -0.305054)
			(stroke
				(width 0.1)
				(type default)
			)
			(layer "B.Fab")
		)
		(fp_line
			(start 0.12065 0.3048)
			(end 0.67945 0.3048)
			(stroke
				(width 0.1)
				(type default)
			)
			(layer "B.Fab")
		)
		(fp_line
			(start 0.12065 0.2794)
			(end 0.12065 0.3048)
			(stroke
				(width 0.1)
				(type default)
			)
			(layer "B.Fab")
		)
		(fp_line
			(start 0.12065 -0.2794)
			(end -0.12065 -0.2794)
			(stroke
				(width 0.1)
				(type default)
			)
			(layer "B.Fab")
		)
		(fp_line
			(start 0.12065 -0.305054)
			(end 0.12065 -0.2794)
			(stroke
				(width 0.1)
				(type default)
			)
			(layer "B.Fab")
		)
		(fp_line
			(start -0.120396 0.3048)
			(end -0.120396 0.2794)
			(stroke
				(width 0.1)
				(type default)
			)
			(layer "B.Fab")
		)
		(fp_line
			(start -0.120396 0.2794)
			(end 0.12065 0.2794)
			(stroke
				(width 0.1)
				(type default)
			)
			(layer "B.Fab")
		)
		(fp_line
			(start -0.12065 -0.2794)
			(end -0.12065 -0.3048)
			(stroke
				(width 0.1)
				(type default)
			)
			(layer "B.Fab")
		)
		(fp_line
			(start -0.12065 -0.3048)
			(end -0.67945 -0.3048)
			(stroke
				(width 0.1)
				(type default)
			)
			(layer "B.Fab")
		)
		(fp_line
			(start -0.67945 0.3048)
			(end -0.120396 0.3048)
			(stroke
				(width 0.1)
				(type default)
			)
			(layer "B.Fab")
		)
		(fp_line
			(start -0.67945 -0.3048)
			(end -0.67945 0.3048)
			(stroke
				(width 0.1)
				(type default)
			)
			(layer "B.Fab")
		)
		(pad "1" smd circle
			(at 0.40005 0)
			(size 0 0)
			(layers "B.Cu" "B.Mask" "B.Paste")
			(net "FM_DB2000_OE_N")
		)
		(pad "2" smd circle
			(at -0.40005 0)
			(size 0 0)
			(layers "B.Cu" "B.Mask" "B.Paste")
			(net "FM_DB2000_1_OE_N")
		)
	)
)
